(kicad_pcb
	(version 20260206)
	(generator "pcbnew")
	(generator_version "10.0")
	(general
		(thickness 1.6)
		(legacy_teardrops no)
	)
	(paper "A4")
	(title_block
		(title "Bryce Canyon_IOM_IOC_16318-2_OCP.brd")
		(comment 1 "Bryce Canyon / footprints 894-899 of 1605")
	)
	(layers
		(0 "F.Cu" signal "TOP")
		(4 "In1.Cu" signal "L2GND")
		(6 "In2.Cu" signal "L3")
		(8 "In3.Cu" signal "L4VCC")
		(10 "In4.Cu" signal "L5VCC")
		(12 "In5.Cu" signal "L6")
		(14 "In6.Cu" signal "L7GND")
		(2 "B.Cu" signal "BOTTOM")
		(9 "F.Adhes" user "F.Adhesive")
		(11 "B.Adhes" user "B.Adhesive")
		(13 "F.Paste" user "Package Geometry/Pastemask Top")
		(15 "B.Paste" user "Package Geometry/Pastemask Bottom")
		(5 "F.SilkS" user "Ref Des/Silkscreen Top")
		(7 "B.SilkS" user "Ref Des/Silkscreen Bottom")
		(1 "F.Mask" user "Board Geometry/Soldermask Top")
		(3 "B.Mask" user "Board Geometry/Soldermask Bottom")
		(17 "Dwgs.User" user "User.Drawings")
		(19 "Cmts.User" user "User.Comments")
		(21 "Eco1.User" user "User.Eco1")
		(23 "Eco2.User" user "User.Eco2")
		(25 "Edge.Cuts" user "Board Geometry/Outline")
		(27 "Margin" user)
		(31 "F.CrtYd" user "Package Geometry/Place Bound Top")
		(29 "B.CrtYd" user "Package Geometry/Place Bound Bottom")
		(35 "F.Fab" user "Ref Des/Assembly Top")
		(33 "B.Fab" user "Ref Des/Assembly Bottom")
	)
	(footprint ""
		(layer "F.Cu")
		(at 10.269982 -172.706284 -90)
		(property "Reference" "R535"
			(at 0 0 270)
			(layer "F.SilkS")
			(hide yes)
			(effects
				(font
					(size 1.27 1.27)
				)
			)
		)
		(property "Value" "0R2J-2-GP"
			(at 0.064008 -3.993896 270)
			(unlocked yes)
			(layer "F.Fab")
			(hide yes)
			(effects
				(font
					(size 1.016 1.016)
					(thickness 0.1524)
				)
			)
		)
		(property "Device Type" "R402H16"
			(at 0.064008 -5.517896 270)
			(unlocked yes)
			(layer "F.Fab")
			(hide yes)
			(effects
				(font
					(size 1.016 1.016)
					(thickness 0.1524)
				)
			)
		)
		(duplicate_pad_numbers_are_jumpers no)
		(fp_line
			(start -0.508 -0.9398)
			(end -0.508 0.9398)
			(stroke
				(width 0.1524)
				(type default)
			)
			(layer "F.SilkS")
		)
		(fp_line
			(start 0.508 -0.9398)
			(end -0.508 -0.9398)
			(stroke
				(width 0.1524)
				(type default)
			)
			(layer "F.SilkS")
		)
		(fp_rect
			(start -0.508 0.9398)
			(end 0.508 -0.9398)
			(stroke
				(width 0)
				(type default)
			)
			(fill no)
			(layer "F.CrtYd")
		)
		(fp_rect
			(start -0.508 0.9398)
			(end 0.508 -0.9398)
			(stroke
				(width 0)
				(type default)
			)
			(fill no)
			(layer "F.Fab")
		)
		(pad "1" smd custom
			(at 0 -0.4445 270)
			(size 0.1397 0.1397)
			(layers "F.Cu" "F.Mask" "F.Paste")
			(net "TPS74801_P1V2_STBY_EN")
			(options
				(clearance outline)
				(anchor circle)
			)
			(primitives
				(gr_poly
					(pts
						(arc
							(start -0.1778 -0.2794)
							(mid -0.249642 -0.249642)
							(end -0.2794 -0.1778)
						)
						(arc
							(start -0.2794 0.1778)
							(mid -0.249642 0.249642)
							(end -0.1778 0.2794)
						)
						(arc
							(start 0.1778 0.2794)
							(mid 0.249642 0.249642)
							(end 0.2794 0.1778)
						)
						(arc
							(start 0.2794 -0.1778)
							(mid 0.249642 -0.249642)
							(end 0.1778 -0.2794)
						)
					)
					(width 0)
					(fill yes)
				)
			)
		)
		(pad "2" smd custom
			(at 0 0.4445 270)
			(size 0.1397 0.1397)
			(layers "F.Cu" "F.Mask" "F.Paste")
			(net "PWRGD_P1V8_STBY")
			(options
				(clearance outline)
				(anchor circle)
			)
			(primitives
				(gr_poly
					(pts
						(arc
							(start -0.1778 -0.2794)
							(mid -0.249642 -0.249642)
							(end -0.2794 -0.1778)
						)
						(arc
							(start -0.2794 0.1778)
							(mid -0.249642 0.249642)
							(end -0.1778 0.2794)
						)
						(arc
							(start 0.1778 0.2794)
							(mid 0.249642 0.249642)
							(end 0.2794 0.1778)
						)
						(arc
							(start 0.2794 -0.1778)
							(mid 0.249642 -0.249642)
							(end 0.1778 -0.2794)
						)
					)
					(width 0)
					(fill yes)
				)
			)
		)
	)
	(footprint ""
		(layer "F.Cu")
		(at 87.294212 -131.339844 90)
		(property "Reference" "R135"
			(at 0 0 90)
			(layer "F.SilkS")
			(hide yes)
			(effects
				(font
					(size 1.27 1.27)
				)
			)
		)
		(property "Value" "8K2R2J-3-GP"
			(at 0.064008 -3.993896 90)
			(unlocked yes)
			(layer "F.Fab")
			(hide yes)
			(effects
				(font
					(size 1.016 1.016)
					(thickness 0.1524)
				)
			)
		)
		(property "Device Type" "R402H16"
			(at 0.064008 -5.517896 90)
			(unlocked yes)
			(layer "F.Fab")
			(hide yes)
			(effects
				(font
					(size 1.016 1.016)
					(thickness 0.1524)
				)
			)
		)
		(duplicate_pad_numbers_are_jumpers no)
		(fp_line
			(start 0.508 -0.9398)
			(end -0.508 -0.9398)
			(stroke
				(width 0.1524)
				(type default)
			)
			(layer "F.SilkS")
		)
		(fp_line
			(start -0.508 -0.9398)
			(end -0.508 0.9398)
			(stroke
				(width 0.1524)
				(type default)
			)
			(layer "F.SilkS")
		)
		(fp_rect
			(start -0.508 0.9398)
			(end 0.508 -0.9398)
			(stroke
				(width 0)
				(type default)
			)
			(fill no)
			(layer "F.CrtYd")
		)
		(fp_rect
			(start -0.508 0.9398)
			(end 0.508 -0.9398)
			(stroke
				(width 0)
				(type default)
			)
			(fill no)
			(layer "F.Fab")
		)
		(pad "1" smd custom
			(at 0 -0.4445 90)
			(size 0.1397 0.1397)
			(layers "F.Cu" "F.Mask" "F.Paste")
			(net "P3V3_STBY")
			(options
				(clearance outline)
				(anchor circle)
			)
			(primitives
				(gr_poly
					(pts
						(arc
							(start -0.1778 -0.2794)
							(mid -0.249642 -0.249642)
							(end -0.2794 -0.1778)
						)
						(arc
							(start -0.2794 0.1778)
							(mid -0.249642 0.249642)
							(end -0.1778 0.2794)
						)
						(arc
							(start 0.1778 0.2794)
							(mid 0.249642 0.249642)
							(end 0.2794 0.1778)
						)
						(arc
							(start 0.2794 -0.1778)
							(mid 0.249642 -0.249642)
							(end 0.1778 -0.2794)
						)
					)
					(width 0)
					(fill yes)
				)
			)
		)
		(pad "2" smd custom
			(at 0 0.4445 90)
			(size 0.1397 0.1397)
			(layers "F.Cu" "F.Mask" "F.Paste")
			(net "EEPROM_A2")
			(options
				(clearance outline)
				(anchor circle)
			)
			(primitives
				(gr_poly
					(pts
						(arc
							(start -0.1778 -0.2794)
							(mid -0.249642 -0.249642)
							(end -0.2794 -0.1778)
						)
						(arc
							(start -0.2794 0.1778)
							(mid -0.249642 0.249642)
							(end -0.1778 0.2794)
						)
						(arc
							(start 0.1778 0.2794)
							(mid 0.249642 0.249642)
							(end 0.2794 0.1778)
						)
						(arc
							(start 0.2794 -0.1778)
							(mid 0.249642 -0.249642)
							(end 0.1778 -0.2794)
						)
					)
					(width 0)
					(fill yes)
				)
			)
		)
	)
	(footprint ""
		(layer "F.Cu")
		(at 35.7378 -165.5572)
		(property "Reference" "R707"
			(at 0 0 0)
			(layer "F.SilkS")
			(hide yes)
			(effects
				(font
					(size 1.27 1.27)
				)
			)
		)
		(property "Value" "4K7R2F-GP"
			(at 0.064008 -3.993896 0)
			(unlocked yes)
			(layer "F.Fab")
			(hide yes)
			(effects
				(font
					(size 1.016 1.016)
					(thickness 0.1524)
				)
			)
		)
		(property "Device Type" "R402H16"
			(at 0.064008 -5.517896 0)
			(unlocked yes)
			(layer "F.Fab")
			(hide yes)
			(effects
				(font
					(size 1.016 1.016)
					(thickness 0.1524)
				)
			)
		)
		(duplicate_pad_numbers_are_jumpers no)
		(fp_line
			(start -0.508 -0.9398)
			(end -0.508 0.9398)
			(stroke
				(width 0.1524)
				(type default)
			)
			(layer "F.SilkS")
		)
		(fp_line
			(start 0.508 -0.9398)
			(end -0.508 -0.9398)
			(stroke
				(width 0.1524)
				(type default)
			)
			(layer "F.SilkS")
		)
		(fp_rect
			(start -0.508 0.9398)
			(end 0.508 -0.9398)
			(stroke
				(width 0)
				(type default)
			)
			(fill no)
			(layer "F.CrtYd")
		)
		(fp_rect
			(start -0.508 0.9398)
			(end 0.508 -0.9398)
			(stroke
				(width 0)
				(type default)
			)
			(fill no)
			(layer "F.Fab")
		)
		(pad "1" smd custom
			(at 0 -0.4445)
			(size 0.1397 0.1397)
			(layers "F.Cu" "F.Mask" "F.Paste")
			(net "P3V3_STBY")
			(options
				(clearance outline)
				(anchor circle)
			)
			(primitives
				(gr_poly
					(pts
						(arc
							(start -0.1778 -0.2794)
							(mid -0.249642 -0.249642)
							(end -0.2794 -0.1778)
						)
						(arc
							(start -0.2794 0.1778)
							(mid -0.249642 0.249642)
							(end -0.1778 0.2794)
						)
						(arc
							(start 0.1778 0.2794)
							(mid 0.249642 0.249642)
							(end 0.2794 0.1778)
						)
						(arc
							(start 0.2794 -0.1778)
							(mid 0.249642 -0.249642)
							(end 0.1778 -0.2794)
						)
					)
					(width 0)
					(fill yes)
				)
			)
		)
		(pad "2" smd custom
			(at 0 0.4445)
			(size 0.1397 0.1397)
			(layers "F.Cu" "F.Mask" "F.Paste")
			(net "IOM_TYPE0")
			(options
				(clearance outline)
				(anchor circle)
			)
			(primitives
				(gr_poly
					(pts
						(arc
							(start -0.1778 -0.2794)
							(mid -0.249642 -0.249642)
							(end -0.2794 -0.1778)
						)
						(arc
							(start -0.2794 0.1778)
							(mid -0.249642 0.249642)
							(end -0.1778 0.2794)
						)
						(arc
							(start 0.1778 0.2794)
							(mid 0.249642 0.249642)
							(end 0.2794 0.1778)
						)
						(arc
							(start 0.2794 -0.1778)
							(mid 0.249642 -0.249642)
							(end 0.1778 -0.2794)
						)
					)
					(width 0)
					(fill yes)
				)
			)
		)
	)
	(footprint ""
		(layer "F.Cu")
		(at 91.639644 -162.52952 -90)
		(property "Reference" "C17"
			(at 0 0 270)
			(layer "F.SilkS")
			(hide yes)
			(effects
				(font
					(size 1.27 1.27)
				)
			)
		)
		(property "Value" "SC18P50V2JN-1-GP"
			(at 1.1811 -2.7051 270)
			(unlocked yes)
			(layer "F.Fab")
			(hide yes)
			(effects
				(font
					(size 1.016 1.016)
					(thickness 0.1524)
				)
			)
		)
		(property "Device Type" "C402H22"
			(at 1.1811 -4.2291 270)
			(unlocked yes)
			(layer "F.Fab")
			(hide yes)
			(effects
				(font
					(size 1.016 1.016)
					(thickness 0.1524)
				)
			)
		)
		(duplicate_pad_numbers_are_jumpers no)
		(fp_rect
			(start -0.4318 0.9525)
			(end 0.4318 -0.9525)
			(stroke
				(width 0)
				(type default)
			)
			(fill no)
			(layer "F.CrtYd")
		)
		(fp_rect
			(start -0.4318 0.9525)
			(end 0.4318 -0.9525)
			(stroke
				(width 0)
				(type default)
			)
			(fill no)
			(layer "F.Fab")
		)
		(pad "1" smd custom
			(at 0 -0.4445 270)
			(size 0.1524 0.1524)
			(layers "F.Cu" "F.Mask" "F.Paste")
			(net "USB_HUB_XTAL_IN")
			(options
				(clearance outline)
				(anchor circle)
			)
			(primitives
				(gr_poly
					(pts
						(arc
							(start 0.3048 -0.2032)
							(mid 0.275042 -0.275042)
							(end 0.2032 -0.3048)
						)
						(arc
							(start -0.2032 -0.3048)
							(mid -0.275042 -0.275042)
							(end -0.3048 -0.2032)
						)
						(arc
							(start -0.3048 0.2032)
							(mid -0.275042 0.275042)
							(end -0.2032 0.3048)
						)
						(arc
							(start 0.2032 0.3048)
							(mid 0.275042 0.275042)
							(end 0.3048 0.2032)
						)
					)
					(width 0)
					(fill yes)
				)
			)
		)
		(pad "2" smd custom
			(at 0 0.4445 270)
			(size 0.1524 0.1524)
			(layers "F.Cu" "F.Mask" "F.Paste")
			(net "GND")
			(options
				(clearance outline)
				(anchor circle)
			)
			(primitives
				(gr_poly
					(pts
						(arc
							(start 0.3048 -0.2032)
							(mid 0.275042 -0.275042)
							(end 0.2032 -0.3048)
						)
						(arc
							(start -0.2032 -0.3048)
							(mid -0.275042 -0.275042)
							(end -0.3048 -0.2032)
						)
						(arc
							(start -0.3048 0.2032)
							(mid -0.275042 0.275042)
							(end -0.2032 0.3048)
						)
						(arc
							(start 0.2032 0.3048)
							(mid 0.275042 0.275042)
							(end 0.3048 0.2032)
						)
					)
					(width 0)
					(fill yes)
				)
			)
		)
	)
	(footprint ""
		(layer "F.Cu")
		(at 73.6092 -168.1988)
		(property "Reference" "R540"
			(at 0 0 0)
			(layer "F.SilkS")
			(hide yes)
			(effects
				(font
					(size 1.27 1.27)
				)
			)
		)
		(property "Value" "0R2J-2-GP"
			(at 0.064008 -3.993896 0)
			(unlocked yes)
			(layer "F.Fab")
			(hide yes)
			(effects
				(font
					(size 1.016 1.016)
					(thickness 0.1524)
				)
			)
		)
		(property "Device Type" "R402H16"
			(at 0.064008 -5.517896 0)
			(unlocked yes)
			(layer "F.Fab")
			(hide yes)
			(effects
				(font
					(size 1.016 1.016)
					(thickness 0.1524)
				)
			)
		)
		(duplicate_pad_numbers_are_jumpers no)
		(fp_line
			(start -0.508 -0.9398)
			(end -0.508 0.9398)
			(stroke
				(width 0.1524)
				(type default)
			)
			(layer "F.SilkS")
		)
		(fp_line
			(start 0.508 -0.9398)
			(end -0.508 -0.9398)
			(stroke
				(width 0.1524)
				(type default)
			)
			(layer "F.SilkS")
		)
		(fp_rect
			(start -0.508 0.9398)
			(end 0.508 -0.9398)
			(stroke
				(width 0)
				(type default)
			)
			(fill no)
			(layer "F.CrtYd")
		)
		(fp_rect
			(start -0.508 0.9398)
			(end 0.508 -0.9398)
			(stroke
				(width 0)
				(type default)
			)
			(fill no)
			(layer "F.Fab")
		)
		(pad "1" smd custom
			(at 0 -0.4445)
			(size 0.1397 0.1397)
			(layers "F.Cu" "F.Mask" "F.Paste")
			(net "P5V_STBY")
			(options
				(clearance outline)
				(anchor circle)
			)
			(primitives
				(gr_poly
					(pts
						(arc
							(start -0.1778 -0.2794)
							(mid -0.249642 -0.249642)
							(end -0.2794 -0.1778)
						)
						(arc
							(start -0.2794 0.1778)
							(mid -0.249642 0.249642)
							(end -0.1778 0.2794)
						)
						(arc
							(start 0.1778 0.2794)
							(mid 0.249642 0.249642)
							(end 0.2794 0.1778)
						)
						(arc
							(start 0.2794 -0.1778)
							(mid 0.249642 -0.249642)
							(end 0.1778 -0.2794)
						)
					)
					(width 0)
					(fill yes)
				)
			)
		)
		(pad "2" smd custom
			(at 0 0.4445)
			(size 0.1397 0.1397)
			(layers "F.Cu" "F.Mask" "F.Paste")
			(net "TPS74801_P1V15_STBY_BIAS")
			(options
				(clearance outline)
				(anchor circle)
			)
			(primitives
				(gr_poly
					(pts
						(arc
							(start -0.1778 -0.2794)
							(mid -0.249642 -0.249642)
							(end -0.2794 -0.1778)
						)
						(arc
							(start -0.2794 0.1778)
							(mid -0.249642 0.249642)
							(end -0.1778 0.2794)
						)
						(arc
							(start 0.1778 0.2794)
							(mid 0.249642 0.249642)
							(end 0.2794 0.1778)
						)
						(arc
							(start 0.2794 -0.1778)
							(mid 0.249642 -0.249642)
							(end 0.1778 -0.2794)
						)
					)
					(width 0)
					(fill yes)
				)
			)
		)
	)
	(footprint ""
		(layer "F.Cu")
		(at 20.591272 -129.074164 180)
		(property "Reference" "R225"
			(at 0 0 180)
			(layer "F.SilkS")
			(hide yes)
			(effects
				(font
					(size 1.27 1.27)
				)
			)
		)
		(property "Value" "120R2F-GP"
			(at 0.064008 -3.993896 180)
			(unlocked yes)
			(layer "F.Fab")
			(hide yes)
			(effects
				(font
					(size 1.016 1.016)
					(thickness 0.1524)
				)
			)
		)
		(property "Device Type" "R402H16"
			(at 0.064008 -5.517896 180)
			(unlocked yes)
			(layer "F.Fab")
			(hide yes)
			(effects
				(font
					(size 1.016 1.016)
					(thickness 0.1524)
				)
			)
		)
		(duplicate_pad_numbers_are_jumpers no)
		(fp_line
			(start 0.508 -0.9398)
			(end -0.508 -0.9398)
			(stroke
				(width 0.1524)
				(type default)
			)
			(layer "F.SilkS")
		)
		(fp_line
			(start -0.508 -0.9398)
			(end -0.508 0.9398)
			(stroke
				(width 0.1524)
				(type default)
			)
			(layer "F.SilkS")
		)
		(fp_rect
			(start -0.508 0.9398)
			(end 0.508 -0.9398)
			(stroke
				(width 0)
				(type default)
			)
			(fill no)
			(layer "F.CrtYd")
		)
		(fp_rect
			(start -0.508 0.9398)
			(end 0.508 -0.9398)
			(stroke
				(width 0)
				(type default)
			)
			(fill no)
			(layer "F.Fab")
		)
		(pad "1" smd custom
			(at 0 -0.4445 180)
			(size 0.1397 0.1397)
			(layers "F.Cu" "F.Mask" "F.Paste")
			(net "GND")
			(options
				(clearance outline)
				(anchor circle)
			)
			(primitives
				(gr_poly
					(pts
						(arc
							(start -0.1778 -0.2794)
							(mid -0.249642 -0.249642)
							(end -0.2794 -0.1778)
						)
						(arc
							(start -0.2794 0.1778)
							(mid -0.249642 0.249642)
							(end -0.1778 0.2794)
						)
						(arc
							(start 0.1778 0.2794)
							(mid 0.249642 0.249642)
							(end 0.2794 0.1778)
						)
						(arc
							(start 0.2794 -0.1778)
							(mid 0.249642 -0.249642)
							(end 0.1778 -0.2794)
						)
					)
					(width 0)
					(fill yes)
				)
			)
		)
		(pad "2" smd custom
			(at 0 0.4445 180)
			(size 0.1397 0.1397)
			(layers "F.Cu" "F.Mask" "F.Paste")
			(net "MEMCASN")
			(options
				(clearance outline)
				(anchor circle)
			)
			(primitives
				(gr_poly
					(pts
						(arc
							(start -0.1778 -0.2794)
							(mid -0.249642 -0.249642)
							(end -0.2794 -0.1778)
						)
						(arc
							(start -0.2794 0.1778)
							(mid -0.249642 0.249642)
							(end -0.1778 0.2794)
						)
						(arc
							(start 0.1778 0.2794)
							(mid 0.249642 0.249642)
							(end 0.2794 0.1778)
						)
						(arc
							(start 0.2794 -0.1778)
							(mid 0.249642 -0.249642)
							(end 0.1778 -0.2794)
						)
					)
					(width 0)
					(fill yes)
				)
			)
		)
	)
)
